(kicad_pcb
	(version 20260206)
	(generator "pcbnew")
	(generator_version "10.0")
	(general
		(thickness 1.6)
		(legacy_teardrops no)
	)
	(paper "A4")
	(title_block
		(title "Bryce Canyon_R.DPB_16317-1_OCP.brd")
		(comment 1 "Bryce Canyon / footprints 687-691 of 2099")
	)
	(layers
		(0 "F.Cu" signal "TOP")
		(4 "In1.Cu" signal "L2GND")
		(6 "In2.Cu" signal "L3")
		(8 "In3.Cu" signal "L4VCC")
		(10 "In4.Cu" signal "L5VCC")
		(12 "In5.Cu" signal "L6")
		(14 "In6.Cu" signal "L7GND")
		(2 "B.Cu" signal "BOTTOM")
		(9 "F.Adhes" user "F.Adhesive")
		(11 "B.Adhes" user "B.Adhesive")
		(13 "F.Paste" user "Package Geometry/Pastemask Top")
		(15 "B.Paste" user "Package Geometry/Pastemask Bottom")
		(5 "F.SilkS" user "Ref Des/Silkscreen Top")
		(7 "B.SilkS" user "Ref Des/Silkscreen Bottom")
		(1 "F.Mask" user "Board Geometry/Soldermask Top")
		(3 "B.Mask" user "Board Geometry/Soldermask Bottom")
		(17 "Dwgs.User" user "User.Drawings")
		(19 "Cmts.User" user "User.Comments")
		(21 "Eco1.User" user "User.Eco1")
		(23 "Eco2.User" user "User.Eco2")
		(25 "Edge.Cuts" user "Board Geometry/Outline")
		(27 "Margin" user)
		(31 "F.CrtYd" user "Package Geometry/Place Bound Top")
		(29 "B.CrtYd" user "Package Geometry/Place Bound Bottom")
		(35 "F.Fab" user "Ref Des/Assembly Top")
		(33 "B.Fab" user "Ref Des/Assembly Bottom")
	)
	(footprint ""
		(layer "F.Cu")
		(at 148.717 -16.3322 -90)
		(property "Reference" "R725"
			(at 0 0 270)
			(layer "F.SilkS")
			(hide yes)
			(effects
				(font
					(size 1.27 1.27)
				)
			)
		)
		(property "Value" "0R2J-2-GP"
			(at 0.064008 -3.993896 270)
			(unlocked yes)
			(layer "F.Fab")
			(hide yes)
			(effects
				(font
					(size 1.016 1.016)
					(thickness 0.1524)
				)
			)
		)
		(property "Device Type" "R402H16"
			(at 0.064008 -5.517896 270)
			(unlocked yes)
			(layer "F.Fab")
			(hide yes)
			(effects
				(font
					(size 1.016 1.016)
					(thickness 0.1524)
				)
			)
		)
		(duplicate_pad_numbers_are_jumpers no)
		(fp_line
			(start -0.508 -0.9398)
			(end -0.508 0.9398)
			(stroke
				(width 0.1524)
				(type default)
			)
			(layer "F.SilkS")
		)
		(fp_line
			(start 0.508 -0.9398)
			(end -0.508 -0.9398)
			(stroke
				(width 0.1524)
				(type default)
			)
			(layer "F.SilkS")
		)
		(fp_rect
			(start -0.508 0.9398)
			(end 0.508 -0.9398)
			(stroke
				(width 0)
				(type default)
			)
			(fill no)
			(layer "F.CrtYd")
		)
		(fp_rect
			(start -0.508 0.9398)
			(end 0.508 -0.9398)
			(stroke
				(width 0)
				(type default)
			)
			(fill no)
			(layer "F.Fab")
		)
		(pad "1" smd custom
			(at 0 -0.4445 270)
			(size 0.1397 0.1397)
			(layers "F.Cu" "F.Mask" "F.Paste")
			(net "DRIVE_B_28_PWR")
			(options
				(clearance outline)
				(anchor circle)
			)
			(primitives
				(gr_poly
					(pts
						(arc
							(start -0.1778 -0.2794)
							(mid -0.249642 -0.249642)
							(end -0.2794 -0.1778)
						)
						(arc
							(start -0.2794 0.1778)
							(mid -0.249642 0.249642)
							(end -0.1778 0.2794)
						)
						(arc
							(start 0.1778 0.2794)
							(mid 0.249642 0.249642)
							(end 0.2794 0.1778)
						)
						(arc
							(start 0.2794 -0.1778)
							(mid 0.249642 -0.249642)
							(end 0.1778 -0.2794)
						)
					)
					(width 0)
					(fill yes)
				)
			)
		)
		(pad "2" smd custom
			(at 0 0.4445 270)
			(size 0.1397 0.1397)
			(layers "F.Cu" "F.Mask" "F.Paste")
			(net "SW_PWR_R_HDD28")
			(options
				(clearance outline)
				(anchor circle)
			)
			(primitives
				(gr_poly
					(pts
						(arc
							(start -0.1778 -0.2794)
							(mid -0.249642 -0.249642)
							(end -0.2794 -0.1778)
						)
						(arc
							(start -0.2794 0.1778)
							(mid -0.249642 0.249642)
							(end -0.1778 0.2794)
						)
						(arc
							(start 0.1778 0.2794)
							(mid 0.249642 0.249642)
							(end 0.2794 0.1778)
						)
						(arc
							(start 0.2794 -0.1778)
							(mid 0.249642 -0.249642)
							(end 0.1778 -0.2794)
						)
					)
					(width 0)
					(fill yes)
				)
			)
		)
	)
	(footprint ""
		(layer "F.Cu")
		(at 352.298 -261.6454 180)
		(property "Reference" "R271"
			(at 0 0 180)
			(layer "F.SilkS")
			(hide yes)
			(effects
				(font
					(size 1.27 1.27)
				)
			)
		)
		(property "Value" "10KR2F-2-GP"
			(at 0.064008 -3.993896 180)
			(unlocked yes)
			(layer "F.Fab")
			(hide yes)
			(effects
				(font
					(size 1.016 1.016)
					(thickness 0.1524)
				)
			)
		)
		(property "Device Type" "R402H16"
			(at 0.064008 -5.517896 180)
			(unlocked yes)
			(layer "F.Fab")
			(hide yes)
			(effects
				(font
					(size 1.016 1.016)
					(thickness 0.1524)
				)
			)
		)
		(duplicate_pad_numbers_are_jumpers no)
		(fp_line
			(start 0.508 -0.9398)
			(end -0.508 -0.9398)
			(stroke
				(width 0.1524)
				(type default)
			)
			(layer "F.SilkS")
		)
		(fp_line
			(start -0.508 -0.9398)
			(end -0.508 0.9398)
			(stroke
				(width 0.1524)
				(type default)
			)
			(layer "F.SilkS")
		)
		(fp_rect
			(start -0.508 0.9398)
			(end 0.508 -0.9398)
			(stroke
				(width 0)
				(type default)
			)
			(fill no)
			(layer "F.CrtYd")
		)
		(fp_rect
			(start -0.508 0.9398)
			(end 0.508 -0.9398)
			(stroke
				(width 0)
				(type default)
			)
			(fill no)
			(layer "F.Fab")
		)
		(pad "1" smd custom
			(at 0 -0.4445 180)
			(size 0.1397 0.1397)
			(layers "F.Cu" "F.Mask" "F.Paste")
			(net "P3V3_STBY_B")
			(options
				(clearance outline)
				(anchor circle)
			)
			(primitives
				(gr_poly
					(pts
						(arc
							(start -0.1778 -0.2794)
							(mid -0.249642 -0.249642)
							(end -0.2794 -0.1778)
						)
						(arc
							(start -0.2794 0.1778)
							(mid -0.249642 0.249642)
							(end -0.1778 0.2794)
						)
						(arc
							(start 0.1778 0.2794)
							(mid 0.249642 0.249642)
							(end 0.2794 0.1778)
						)
						(arc
							(start 0.2794 -0.1778)
							(mid 0.249642 -0.249642)
							(end 0.1778 -0.2794)
						)
					)
					(width 0)
					(fill yes)
				)
			)
		)
		(pad "2" smd custom
			(at 0 0.4445 180)
			(size 0.1397 0.1397)
			(layers "F.Cu" "F.Mask" "F.Paste")
			(net "HDD_PRSNT_7")
			(options
				(clearance outline)
				(anchor circle)
			)
			(primitives
				(gr_poly
					(pts
						(arc
							(start -0.1778 -0.2794)
							(mid -0.249642 -0.249642)
							(end -0.2794 -0.1778)
						)
						(arc
							(start -0.2794 0.1778)
							(mid -0.249642 0.249642)
							(end -0.1778 0.2794)
						)
						(arc
							(start 0.1778 0.2794)
							(mid 0.249642 0.249642)
							(end 0.2794 0.1778)
						)
						(arc
							(start 0.2794 -0.1778)
							(mid 0.249642 -0.249642)
							(end 0.1778 -0.2794)
						)
					)
					(width 0)
					(fill yes)
				)
			)
		)
	)
	(footprint ""
		(layer "F.Cu")
		(at 246.486934 -139.591034 -90)
		(property "Reference" "U24"
			(at 0 0 270)
			(layer "F.SilkS")
			(hide yes)
			(effects
				(font
					(size 1.27 1.27)
				)
			)
		)
		(property "Value" "PCA9511ADP-T-GP"
			(at 0 -13.1572 270)
			(unlocked yes)
			(layer "F.Fab")
			(hide yes)
			(effects
				(font
					(size 1.016 1.016)
					(thickness 0.1524)
				)
			)
		)
		(property "Device Type" "SSOIC8-2H44"
			(at 0 -15.1892 270)
			(unlocked yes)
			(layer "F.Fab")
			(hide yes)
			(effects
				(font
					(size 1.016 1.016)
					(thickness 0.1524)
				)
			)
		)
		(duplicate_pad_numbers_are_jumpers no)
		(fp_line
			(start -1.7018 1.0414)
			(end -1.7018 2.9718)
			(stroke
				(width 0.635)
				(type default)
			)
			(layer "F.SilkS")
		)
		(fp_line
			(start -1.9304 1.016)
			(end -1.9304 -1.016)
			(stroke
				(width 0.1524)
				(type default)
			)
			(layer "F.SilkS")
		)
		(fp_line
			(start 1.0922 1.016)
			(end -1.9304 1.016)
			(stroke
				(width 0.1524)
				(type default)
			)
			(layer "F.SilkS")
		)
		(fp_line
			(start -1.524 0)
			(end -1.9304 0.4064)
			(stroke
				(width 0.1524)
				(type default)
			)
			(layer "F.SilkS")
		)
		(fp_line
			(start -1.524 0)
			(end -1.9304 -0.4064)
			(stroke
				(width 0.1524)
				(type default)
			)
			(layer "F.SilkS")
		)
		(fp_line
			(start -1.9304 -1.016)
			(end 1.0922 -1.016)
			(stroke
				(width 0.1524)
				(type default)
			)
			(layer "F.SilkS")
		)
		(fp_line
			(start 1.0922 -1.016)
			(end 1.0922 1.016)
			(stroke
				(width 0.1524)
				(type default)
			)
			(layer "F.SilkS")
		)
		(fp_poly
			(pts
				(xy -1.1938 -1.016) (xy 1.0922 -1.016) (xy 1.0922 1.016) (xy -1.1938 1.016)
			)
			(stroke
				(width 0)
				(type default)
			)
			(fill yes)
			(layer "F.SilkS")
		)
		(fp_rect
			(start -2.0066 3.3401)
			(end 2.0066 -3.3401)
			(stroke
				(width 0)
				(type default)
			)
			(fill no)
			(layer "F.CrtYd")
		)
		(fp_poly
			(pts
				(xy -2.0066 -3.3401) (xy 2.0066 -3.3401) (xy 2.0066 3.3401) (xy -2.0066 3.3401)
			)
			(stroke
				(width 0)
				(type default)
			)
			(fill no)
			(layer "F.Fab")
		)
		(pad "1" smd rect
			(at -0.97536 2.0701 270)
			(size 0.4064 1.524)
			(layers "F.Cu" "F.Mask" "F.Paste")
			(net "I2C_SCC_BUFF_EN")
		)
		(pad "2" smd rect
			(at -0.32512 2.0701 270)
			(size 0.4064 1.524)
			(layers "F.Cu" "F.Mask" "F.Paste")
			(net "I2C_SCC_B_SCL_BUF")
		)
		(pad "3" smd rect
			(at 0.32512 2.0701 270)
			(size 0.4064 1.524)
			(layers "F.Cu" "F.Mask" "F.Paste")
			(net "I2C_SCC_B_SCL")
		)
		(pad "4" smd rect
			(at 0.97536 2.0701 270)
			(size 0.4064 1.524)
			(layers "F.Cu" "F.Mask" "F.Paste")
			(net "GND")
		)
		(pad "5" smd rect
			(at 0.97536 -2.0701 270)
			(size 0.4064 1.524)
			(layers "F.Cu" "F.Mask" "F.Paste")
			(net "I2C_SCC_BUFF_READY")
		)
		(pad "6" smd rect
			(at 0.32512 -2.0701 270)
			(size 0.4064 1.524)
			(layers "F.Cu" "F.Mask" "F.Paste")
			(net "I2C_SCC_B_SDA")
		)
		(pad "7" smd rect
			(at -0.32512 -2.0701 270)
			(size 0.4064 1.524)
			(layers "F.Cu" "F.Mask" "F.Paste")
			(net "I2C_SCC_B_SDA_BUF")
		)
		(pad "8" smd rect
			(at -0.97536 -2.0701 270)
			(size 0.4064 1.524)
			(layers "F.Cu" "F.Mask" "F.Paste")
			(net "P3V3_STBY_B")
		)
	)
	(footprint ""
		(layer "F.Cu")
		(at 246.745252 -368.784632)
		(property "Reference" "C553"
			(at 0 0 0)
			(layer "F.SilkS")
			(hide yes)
			(effects
				(font
					(size 1.27 1.27)
				)
			)
		)
		(property "Value" "SC1KP50V2KX-1GP"
			(at 1.1811 -2.7051 0)
			(unlocked yes)
			(layer "F.Fab")
			(hide yes)
			(effects
				(font
					(size 1.016 1.016)
					(thickness 0.1524)
				)
			)
		)
		(property "Device Type" "C402H22"
			(at 1.1811 -4.2291 0)
			(unlocked yes)
			(layer "F.Fab")
			(hide yes)
			(effects
				(font
					(size 1.016 1.016)
					(thickness 0.1524)
				)
			)
		)
		(duplicate_pad_numbers_are_jumpers no)
		(fp_rect
			(start -0.4318 0.9525)
			(end 0.4318 -0.9525)
			(stroke
				(width 0)
				(type default)
			)
			(fill no)
			(layer "F.CrtYd")
		)
		(fp_rect
			(start -0.4318 0.9525)
			(end 0.4318 -0.9525)
			(stroke
				(width 0)
				(type default)
			)
			(fill no)
			(layer "F.Fab")
		)
		(pad "1" smd custom
			(at 0 -0.4445)
			(size 0.1524 0.1524)
			(layers "F.Cu" "F.Mask" "F.Paste")
			(net "MB3_TEMP_B")
			(options
				(clearance outline)
				(anchor circle)
			)
			(primitives
				(gr_poly
					(pts
						(arc
							(start 0.3048 -0.2032)
							(mid 0.275042 -0.275042)
							(end 0.2032 -0.3048)
						)
						(arc
							(start -0.2032 -0.3048)
							(mid -0.275042 -0.275042)
							(end -0.3048 -0.2032)
						)
						(arc
							(start -0.3048 0.2032)
							(mid -0.275042 0.275042)
							(end -0.2032 0.3048)
						)
						(arc
							(start 0.2032 0.3048)
							(mid 0.275042 0.275042)
							(end 0.3048 0.2032)
						)
					)
					(width 0)
					(fill yes)
				)
			)
		)
		(pad "2" smd custom
			(at 0 0.4445)
			(size 0.1524 0.1524)
			(layers "F.Cu" "F.Mask" "F.Paste")
			(net "MB3_TEMP_E")
			(options
				(clearance outline)
				(anchor circle)
			)
			(primitives
				(gr_poly
					(pts
						(arc
							(start 0.3048 -0.2032)
							(mid 0.275042 -0.275042)
							(end 0.2032 -0.3048)
						)
						(arc
							(start -0.2032 -0.3048)
							(mid -0.275042 -0.275042)
							(end -0.3048 -0.2032)
						)
						(arc
							(start -0.3048 0.2032)
							(mid -0.275042 0.275042)
							(end -0.2032 0.3048)
						)
						(arc
							(start 0.2032 0.3048)
							(mid 0.275042 0.275042)
							(end 0.3048 0.2032)
						)
					)
					(width 0)
					(fill yes)
				)
			)
		)
	)
	(footprint ""
		(layer "F.Cu")
		(at 32.463486 -14.660626 90)
		(property "Reference" "C341"
			(at 0 0 90)
			(layer "F.SilkS")
			(hide yes)
			(effects
				(font
					(size 1.27 1.27)
				)
			)
		)
		(property "Value" "SCD01U16V1KX-GP"
			(at -2.8321 -1.7399 90)
			(unlocked yes)
			(layer "F.Fab")
			(hide yes)
			(effects
				(font
					(size 1.016 1.016)
					(thickness 0.1524)
				)
			)
		)
		(property "Device Type" "C0201H13"
			(at -2.8321 -3.2639 90)
			(unlocked yes)
			(layer "F.Fab")
			(hide yes)
			(effects
				(font
					(size 1.016 1.016)
					(thickness 0.1524)
				)
			)
		)
		(duplicate_pad_numbers_are_jumpers no)
		(fp_rect
			(start -0.2794 0.6477)
			(end 0.2794 -0.6477)
			(stroke
				(width 0)
				(type default)
			)
			(fill no)
			(layer "F.CrtYd")
		)
		(fp_rect
			(start -0.2794 0.6477)
			(end 0.2794 -0.6477)
			(stroke
				(width 0)
				(type default)
			)
			(fill no)
			(layer "F.Fab")
		)
		(pad "1" smd custom
			(at 0 -0.2794 90)
			(size 0.0762 0.0762)
			(layers "F.Cu" "F.Mask" "F.Paste")
			(net "SAS_HDD_RX_P24")
			(options
				(clearance outline)
				(anchor circle)
			)
			(primitives
				(gr_poly
					(pts
						(arc
							(start 0.1524 -0.127)
							(mid 0.137521 -0.162921)
							(end 0.1016 -0.1778)
						)
						(arc
							(start -0.1016 -0.1778)
							(mid -0.137521 -0.162921)
							(end -0.1524 -0.127)
						)
						(arc
							(start -0.1524 0.127)
							(mid -0.137521 0.162921)
							(end -0.1016 0.1778)
						)
						(arc
							(start 0.1016 0.1778)
							(mid 0.137521 0.162921)
							(end 0.1524 0.127)
						)
					)
					(width 0)
					(fill yes)
				)
			)
		)
		(pad "2" smd custom
			(at 0 0.2794 90)
			(size 0.0762 0.0762)
			(layers "F.Cu" "F.Mask" "F.Paste")
			(net "PHY_SCC_B_TO_DRV_B_24_DP")
			(options
				(clearance outline)
				(anchor circle)
			)
			(primitives
				(gr_poly
					(pts
						(arc
							(start 0.1524 -0.127)
							(mid 0.137521 -0.162921)
							(end 0.1016 -0.1778)
						)
						(arc
							(start -0.1016 -0.1778)
							(mid -0.137521 -0.162921)
							(end -0.1524 -0.127)
						)
						(arc
							(start -0.1524 0.127)
							(mid -0.137521 0.162921)
							(end -0.1016 0.1778)
						)
						(arc
							(start 0.1016 0.1778)
							(mid 0.137521 0.162921)
							(end 0.1524 0.127)
						)
					)
					(width 0)
					(fill yes)
				)
			)
		)
	)
)
